# BASEBOARD_FAB2 (Tioga Pass) — schematic netlist excerpt (pin names and nets, part order shuffled) for the footprints in the layout excerpt that follows; sources: Cadence DE-HDL packaged netlist, KiCad conversion of Wiwynn_Tioga_Pass_MB.brd

F8B1  FUSE-3A75V-GP  pkg DISCRET-G5  page 172 : \1\ = P5V_HDD_SATA ; \2\ = P5V
R8E4  RES  1.00K 1% EMPTY  pkg 0402  page 125 : A = SPI_PCH_MOSI ; B = GND
R25W89  RES  22.1 1.0% CHIP  pkg 0402  page 147 : A = RMII_BMC_PCH_SPRNGVLLE_TXD0_R ; B = RMII_BMC_PCH_SPRNGVLLE_TXD0

(kicad_pcb
	(version 20260206)
	(generator "pcbnew")
	(generator_version "10.0")
	(general
		(thickness 1.6)
		(legacy_teardrops no)
	)
	(paper "A4")
	(title_block
		(title "Wiwynn_Tioga_Pass_MB.brd")
		(comment 1 "Tioga Pass / footprints 681-683 of 4770")
	)
	(layers
		(0 "F.Cu" signal "TOP")
		(4 "In1.Cu" signal "L2GND")
		(6 "In2.Cu" signal "L3")
		(8 "In3.Cu" signal "L4GND")
		(10 "In4.Cu" signal "L5")
		(12 "In5.Cu" signal "L6GND")
		(14 "In6.Cu" signal "L7VCC")
		(16 "In7.Cu" signal "L8VCC")
		(18 "In8.Cu" signal "L9GND")
		(20 "In9.Cu" signal "L10")
		(22 "In10.Cu" signal "L11GND")
		(24 "In11.Cu" signal "L12")
		(26 "In12.Cu" signal "L13GND")
		(2 "B.Cu" signal "BOTTOM")
		(9 "F.Adhes" user "F.Adhesive")
		(11 "B.Adhes" user "B.Adhesive")
		(13 "F.Paste" user "Package Geometry/Pastemask Top")
		(15 "B.Paste" user "Package Geometry/Pastemask Bottom")
		(5 "F.SilkS" user "Ref Des/Silkscreen Top")
		(7 "B.SilkS" user "Ref Des/Silkscreen Bottom")
		(1 "F.Mask" user "Board Geometry/Soldermask Top")
		(3 "B.Mask" user "Board Geometry/Soldermask Bottom")
		(17 "Dwgs.User" user "User.Drawings")
		(19 "Cmts.User" user "User.Comments")
		(21 "Eco1.User" user "User.Eco1")
		(23 "Eco2.User" user "User.Eco2")
		(25 "Edge.Cuts" user "Board Geometry/Outline")
		(27 "Margin" user)
		(31 "F.CrtYd" user "Package Geometry/Place Bound Top")
		(29 "B.CrtYd" user "Package Geometry/Place Bound Bottom")
		(35 "F.Fab" user "Ref Des/Assembly Top")
		(33 "B.Fab" user "Ref Des/Assembly Bottom")
	)
	(footprint ""
		(layer "F.Cu")
		(at 405.257 -23.0505)
		(property "Reference" "R25W89"
			(at -0.8382 -0.67818 0)
			(unlocked yes)
			(layer "F.SilkS")
			(effects
				(font
					(size 0.4064 0.254)
					(thickness 0.1524)
				)
				(justify left)
			)
		)
		(property "Value" ""
			(at 0 0 0)
			(layer "F.Fab")
			(effects
				(font
					(size 1.27 1.27)
				)
			)
		)
		(duplicate_pad_numbers_are_jumpers no)
		(fp_poly
			(pts
				(xy -0.2794 -0.1016) (xy 0.2794 -0.1016) (xy 0.2794 0.9906) (xy -0.2794 0.9906)
			)
			(stroke
				(width 0)
				(type default)
			)
			(fill no)
			(layer "F.CrtYd")
		)
		(fp_line
			(start -0.2794 -0.1016)
			(end -0.2794 0.9906)
			(stroke
				(width 0.1)
				(type default)
			)
			(layer "F.Fab")
		)
		(fp_line
			(start -0.2794 0.9906)
			(end 0.2794 0.9906)
			(stroke
				(width 0.1)
				(type default)
			)
			(layer "F.Fab")
		)
		(fp_line
			(start 0.2794 -0.1016)
			(end -0.2794 -0.1016)
			(stroke
				(width 0.1)
				(type default)
			)
			(layer "F.Fab")
		)
		(fp_line
			(start 0.2794 0.9906)
			(end 0.2794 -0.1016)
			(stroke
				(width 0.1)
				(type default)
			)
			(layer "F.Fab")
		)
		(pad "1" smd rect
			(at 0 0)
			(size 0.508 0.508)
			(layers "F.Cu" "F.Mask" "F.Paste")
			(net "RMII_BMC_PCH_SPRNGVLLE_TXD0_R")
		)
		(pad "2" smd rect
			(at 0 0.889)
			(size 0.508 0.508)
			(layers "F.Cu" "F.Mask" "F.Paste")
			(net "RMII_BMC_PCH_SPRNGVLLE_TXD0")
		)
		(zone
			(layer "F.Cu")
			(hatch none 0.5)
			(connect_pads
				(clearance 0)
			)
			(min_thickness 0.25)
			(keepout
				(tracks allowed)
				(vias not_allowed)
				(pads allowed)
				(copperpour not_allowed)
				(footprints allowed)
			)
			(placement
				(enabled no)
				(sheetname "")
			)
			(fill
				(thermal_gap 0.5)
				(thermal_bridge_width 0.5)
				(island_removal_mode 0)
			)
			(polygon
				(pts
					(xy 405.003 -22.7965) (xy 405.511 -22.7965) (xy 405.511 -22.4155) (xy 405.003 -22.4155)
				)
			)
		)
		(zone
			(layer "F.Cu")
			(hatch none 0.5)
			(connect_pads
				(clearance 0)
			)
			(min_thickness 0.25)
			(keepout
				(tracks not_allowed)
				(vias allowed)
				(pads allowed)
				(copperpour not_allowed)
				(footprints allowed)
			)
			(placement
				(enabled no)
				(sheetname "")
			)
			(fill
				(thermal_gap 0.5)
				(thermal_bridge_width 0.5)
				(island_removal_mode 0)
			)
			(polygon
				(pts
					(xy 405.003 -22.4155) (xy 405.511 -22.4155) (xy 405.511 -22.7965) (xy 405.003 -22.7965)
				)
			)
		)
	)
	(footprint ""
		(layer "F.Cu")
		(at 406.9461 -64.135 90)
		(property "Reference" "R8E4"
			(at 0 0 90)
			(layer "F.SilkS")
			(hide yes)
			(effects
				(font
					(size 1.27 1.27)
				)
			)
		)
		(property "Value" ""
			(at 0 0 90)
			(layer "F.Fab")
			(effects
				(font
					(size 1.27 1.27)
				)
			)
		)
		(duplicate_pad_numbers_are_jumpers no)
		(fp_poly
			(pts
				(xy -0.2794 -0.1016) (xy 0.2794 -0.1016) (xy 0.2794 0.9906) (xy -0.2794 0.9906)
			)
			(stroke
				(width 0)
				(type default)
			)
			(fill no)
			(layer "F.CrtYd")
		)
		(pad "1" smd rect
			(at 0 0 90)
			(size 0.508 0.508)
			(layers "F.Cu" "F.Mask" "F.Paste")
			(net "SPI_PCH_MOSI")
		)
		(pad "2" smd rect
			(at 0 0.889 90)
			(size 0.508 0.508)
			(layers "F.Cu" "F.Mask" "F.Paste")
			(net "GND")
		)
		(zone
			(layer "F.Cu")
			(hatch none 0.5)
			(connect_pads
				(clearance 0)
			)
			(min_thickness 0.25)
			(keepout
				(tracks allowed)
				(vias not_allowed)
				(pads allowed)
				(copperpour not_allowed)
				(footprints allowed)
			)
			(placement
				(enabled no)
				(sheetname "")
			)
			(fill
				(thermal_gap 0.5)
				(thermal_bridge_width 0.5)
				(island_removal_mode 0)
			)
			(polygon
				(pts
					(xy 407.2001 -63.881) (xy 407.2001 -64.389) (xy 407.5811 -64.389) (xy 407.5811 -63.881)
				)
			)
		)
		(zone
			(layer "F.Cu")
			(hatch none 0.5)
			(connect_pads
				(clearance 0)
			)
			(min_thickness 0.25)
			(keepout
				(tracks not_allowed)
				(vias allowed)
				(pads allowed)
				(copperpour not_allowed)
				(footprints allowed)
			)
			(placement
				(enabled no)
				(sheetname "")
			)
			(fill
				(thermal_gap 0.5)
				(thermal_bridge_width 0.5)
				(island_removal_mode 0)
			)
			(polygon
				(pts
					(xy 407.5811 -63.881) (xy 407.5811 -64.389) (xy 407.2001 -64.389) (xy 407.2001 -63.881)
				)
			)
		)
	)
	(footprint ""
		(layer "F.Cu")
		(at 442.89472 -129.58318)
		(property "Reference" "F8B1"
			(at 0 0 0)
			(layer "F.SilkS")
			(hide yes)
			(effects
				(font
					(size 1.27 1.27)
				)
			)
		)
		(property "Value" "*"
			(at -0.02032 -4.5212 0)
			(unlocked yes)
			(layer "F.Fab")
			(hide yes)
			(effects
				(font
					(size 1.27 1.016)
					(thickness 0.1524)
				)
			)
		)
		(property "Device Type" "FUSE-3A75V-GP_DISCRET-G5-FUSE-A"
			(at -0.02032 -6.0452 0)
			(unlocked yes)
			(layer "F.Fab")
			(hide yes)
			(effects
				(font
					(size 1.27 1.016)
					(thickness 0.1524)
				)
			)
		)
		(duplicate_pad_numbers_are_jumpers no)
		(fp_line
			(start -1.1684 -2.2225)
			(end -1.1684 2.2225)
			(stroke
				(width 0.1524)
				(type default)
			)
			(layer "F.SilkS")
		)
		(fp_line
			(start -1.1684 2.2225)
			(end 1.1684 2.2225)
			(stroke
				(width 0.1524)
				(type default)
			)
			(layer "F.SilkS")
		)
		(fp_line
			(start 1.1684 -2.2225)
			(end -1.1684 -2.2225)
			(stroke
				(width 0.1524)
				(type default)
			)
			(layer "F.SilkS")
		)
		(fp_line
			(start 1.1684 2.2225)
			(end 1.1684 -2.2225)
			(stroke
				(width 0.1524)
				(type default)
			)
			(layer "F.SilkS")
		)
		(fp_rect
			(start -0.7874 1.5875)
			(end 0.7874 -1.5875)
			(stroke
				(width 0)
				(type default)
			)
			(fill no)
			(layer "F.CrtYd")
		)
		(fp_poly
			(pts
				(xy -1.4224 2.2987) (xy -1.4224 -2.2987) (xy 1.4224 -2.2987) (xy 1.4224 -0.25146) (xy 0.7874 -0.25146)
				(xy 0.7874 -1.5875) (xy -0.7874 -1.5875) (xy -0.7874 1.5875) (xy 0.7874 1.5875) (xy 0.7874 -0.24892)
				(xy 1.4224 -0.24892) (xy 1.4224 2.2987)
			)
			(stroke
				(width 0)
				(type default)
			)
			(fill no)
			(layer "F.CrtYd")
		)
		(fp_rect
			(start -1.4224 2.2987)
			(end 1.4224 -2.2987)
			(stroke
				(width 0)
				(type default)
			)
			(fill no)
			(layer "F.Fab")
		)
		(pad "1" smd rect
			(at 0 -1.2446)
			(size 1.8288 1.4478)
			(layers "F.Cu" "F.Mask" "F.Paste")
			(net "P5V_HDD_SATA")
		)
		(pad "2" smd rect
			(at 0 1.2446)
			(size 1.8288 1.4478)
			(layers "F.Cu" "F.Mask" "F.Paste")
			(net "P5V")
		)
	)
)
